# SCM (Grand Teton) — schematic netlist excerpt (pin names and nets, part order shuffled) for the footprints in the layout excerpt that follows; sources: Cadence DE-HDL packaged netlist, KiCad conversion of 12092022_DA0F0TMDCD0_F0T_Management_Board_D_brd_V3_OCP.brd

R121  Q_RES  33.2 1% CHIP  pkg 0402LF  page 13 : A = FM_CPU_RMCA_CATERR_LVT3_R_N ; B = FM_CPU_MSMI_CATERR_LVT3_N
R641  Q_RES  4.7K 1% EMPTY  pkg 0402LF  page 42 : A = P3V3_AUX ; B = RST_BMC_SELF_HW_R2

(kicad_pcb
	(version 20260206)
	(generator "pcbnew")
	(generator_version "10.0")
	(general
		(thickness 1.6)
		(legacy_teardrops no)
	)
	(paper "A4")
	(title_block
		(title "12092022_DA0F0TMDCD0_F0T_Management_Board_D_brd_V3_OCP.brd")
		(comment 1 "Grand Teton / footprints 1349-1350 of 1440")
	)
	(layers
		(0 "F.Cu" signal "TOP")
		(4 "In1.Cu" signal "GND")
		(6 "In2.Cu" signal "IN1")
		(8 "In3.Cu" signal "GND1")
		(10 "In4.Cu" signal "IN2")
		(12 "In5.Cu" signal "VCC")
		(14 "In6.Cu" signal "VCC1")
		(16 "In7.Cu" signal "IN3")
		(18 "In8.Cu" signal "GND2")
		(20 "In9.Cu" signal "IN4")
		(22 "In10.Cu" signal "GND3")
		(2 "B.Cu" signal "BOTTOM")
		(9 "F.Adhes" user "F.Adhesive")
		(11 "B.Adhes" user "B.Adhesive")
		(13 "F.Paste" user "Package Geometry/Pastemask Top")
		(15 "B.Paste" user "Package Geometry/Pastemask Bottom")
		(5 "F.SilkS" user "Ref Des/Silkscreen Top")
		(7 "B.SilkS" user "Ref Des/Silkscreen Bottom")
		(1 "F.Mask" user "Board Geometry/Soldermask Top")
		(3 "B.Mask" user "Board Geometry/Soldermask Bottom")
		(17 "Dwgs.User" user "User.Drawings")
		(19 "Cmts.User" user "User.Comments")
		(21 "Eco1.User" user "User.Eco1")
		(23 "Eco2.User" user "User.Eco2")
		(25 "Edge.Cuts" user "Board Geometry/Outline")
		(27 "Margin" user)
		(31 "F.CrtYd" user "Package Geometry/Place Bound Top")
		(29 "B.CrtYd" user "Package Geometry/Place Bound Bottom")
		(35 "F.Fab" user "Ref Des/Assembly Top")
		(33 "B.Fab" user "Ref Des/Assembly Bottom")
	)
	(footprint ""
		(layer "B.Cu")
		(at 34.417 -36.195 90)
		(property "Reference" "R121"
			(at 0 0 90)
			(layer "B.SilkS")
			(hide yes)
			(effects
				(font
					(size 1.27 1.27)
				)
				(justify mirror)
			)
		)
		(property "Value" ""
			(at 0 0 90)
			(layer "B.Fab")
			(effects
				(font
					(size 1.27 1.27)
				)
				(justify mirror)
			)
		)
		(duplicate_pad_numbers_are_jumpers no)
		(fp_line
			(start 0.7874 -0.4064)
			(end -0.7874 -0.4064)
			(stroke
				(width 0.1524)
				(type default)
			)
			(layer "B.SilkS")
		)
		(fp_line
			(start -0.7874 -0.4064)
			(end -0.7874 0.4064)
			(stroke
				(width 0.1524)
				(type default)
			)
			(layer "B.SilkS")
		)
		(fp_line
			(start 0.7874 0.4064)
			(end 0.7874 -0.4064)
			(stroke
				(width 0.1524)
				(type default)
			)
			(layer "B.SilkS")
		)
		(fp_line
			(start -0.7874 0.4064)
			(end 0.7874 0.4064)
			(stroke
				(width 0.1524)
				(type default)
			)
			(layer "B.SilkS")
		)
		(fp_line
			(start 0.67945 -0.305054)
			(end 0.12065 -0.305054)
			(stroke
				(width 0.1)
				(type default)
			)
			(layer "B.Fab")
		)
		(fp_line
			(start 0.12065 -0.305054)
			(end 0.12065 -0.2794)
			(stroke
				(width 0.1)
				(type default)
			)
			(layer "B.Fab")
		)
		(fp_line
			(start -0.12065 -0.3048)
			(end -0.67945 -0.3048)
			(stroke
				(width 0.1)
				(type default)
			)
			(layer "B.Fab")
		)
		(fp_line
			(start -0.67945 -0.3048)
			(end -0.67945 0.3048)
			(stroke
				(width 0.1)
				(type default)
			)
			(layer "B.Fab")
		)
		(fp_line
			(start 0.12065 -0.2794)
			(end -0.12065 -0.2794)
			(stroke
				(width 0.1)
				(type default)
			)
			(layer "B.Fab")
		)
		(fp_line
			(start -0.12065 -0.2794)
			(end -0.12065 -0.3048)
			(stroke
				(width 0.1)
				(type default)
			)
			(layer "B.Fab")
		)
		(fp_line
			(start 0.12065 0.2794)
			(end 0.12065 0.3048)
			(stroke
				(width 0.1)
				(type default)
			)
			(layer "B.Fab")
		)
		(fp_line
			(start -0.120396 0.2794)
			(end 0.12065 0.2794)
			(stroke
				(width 0.1)
				(type default)
			)
			(layer "B.Fab")
		)
		(fp_line
			(start 0.67945 0.3048)
			(end 0.67945 -0.305054)
			(stroke
				(width 0.1)
				(type default)
			)
			(layer "B.Fab")
		)
		(fp_line
			(start 0.12065 0.3048)
			(end 0.67945 0.3048)
			(stroke
				(width 0.1)
				(type default)
			)
			(layer "B.Fab")
		)
		(fp_line
			(start -0.120396 0.3048)
			(end -0.120396 0.2794)
			(stroke
				(width 0.1)
				(type default)
			)
			(layer "B.Fab")
		)
		(fp_line
			(start -0.67945 0.3048)
			(end -0.120396 0.3048)
			(stroke
				(width 0.1)
				(type default)
			)
			(layer "B.Fab")
		)
		(pad "1" smd circle
			(at 0.40005 0 270)
			(size 0 0)
			(layers "B.Cu" "B.Mask" "B.Paste")
			(net "FM_CPU_RMCA_CATERR_LVT3_R_N")
		)
		(pad "2" smd circle
			(at -0.40005 0 270)
			(size 0 0)
			(layers "B.Cu" "B.Mask" "B.Paste")
			(net "FM_CPU_MSMI_CATERR_LVT3_N")
		)
	)
	(footprint ""
		(layer "B.Cu")
		(at 12.7 -90.043 90)
		(property "Reference" "R641"
			(at 0 0 90)
			(layer "B.SilkS")
			(hide yes)
			(effects
				(font
					(size 1.27 1.27)
				)
				(justify mirror)
			)
		)
		(property "Value" ""
			(at 0 0 90)
			(layer "B.Fab")
			(effects
				(font
					(size 1.27 1.27)
				)
				(justify mirror)
			)
		)
		(duplicate_pad_numbers_are_jumpers no)
		(fp_line
			(start 0.7874 -0.4064)
			(end -0.7874 -0.4064)
			(stroke
				(width 0.1524)
				(type default)
			)
			(layer "B.SilkS")
		)
		(fp_line
			(start -0.7874 -0.4064)
			(end -0.7874 0.4064)
			(stroke
				(width 0.1524)
				(type default)
			)
			(layer "B.SilkS")
		)
		(fp_line
			(start 0.7874 0.4064)
			(end 0.7874 -0.4064)
			(stroke
				(width 0.1524)
				(type default)
			)
			(layer "B.SilkS")
		)
		(fp_line
			(start -0.7874 0.4064)
			(end 0.7874 0.4064)
			(stroke
				(width 0.1524)
				(type default)
			)
			(layer "B.SilkS")
		)
		(fp_line
			(start 0.67945 -0.305054)
			(end 0.12065 -0.305054)
			(stroke
				(width 0.1)
				(type default)
			)
			(layer "B.Fab")
		)
		(fp_line
			(start 0.12065 -0.305054)
			(end 0.12065 -0.2794)
			(stroke
				(width 0.1)
				(type default)
			)
			(layer "B.Fab")
		)
		(fp_line
			(start -0.12065 -0.3048)
			(end -0.67945 -0.3048)
			(stroke
				(width 0.1)
				(type default)
			)
			(layer "B.Fab")
		)
		(fp_line
			(start -0.67945 -0.3048)
			(end -0.67945 0.3048)
			(stroke
				(width 0.1)
				(type default)
			)
			(layer "B.Fab")
		)
		(fp_line
			(start 0.12065 -0.2794)
			(end -0.12065 -0.2794)
			(stroke
				(width 0.1)
				(type default)
			)
			(layer "B.Fab")
		)
		(fp_line
			(start -0.12065 -0.2794)
			(end -0.12065 -0.3048)
			(stroke
				(width 0.1)
				(type default)
			)
			(layer "B.Fab")
		)
		(fp_line
			(start 0.12065 0.2794)
			(end 0.12065 0.3048)
			(stroke
				(width 0.1)
				(type default)
			)
			(layer "B.Fab")
		)
		(fp_line
			(start -0.120396 0.2794)
			(end 0.12065 0.2794)
			(stroke
				(width 0.1)
				(type default)
			)
			(layer "B.Fab")
		)
		(fp_line
			(start 0.67945 0.3048)
			(end 0.67945 -0.305054)
			(stroke
				(width 0.1)
				(type default)
			)
			(layer "B.Fab")
		)
		(fp_line
			(start 0.12065 0.3048)
			(end 0.67945 0.3048)
			(stroke
				(width 0.1)
				(type default)
			)
			(layer "B.Fab")
		)
		(fp_line
			(start -0.120396 0.3048)
			(end -0.120396 0.2794)
			(stroke
				(width 0.1)
				(type default)
			)
			(layer "B.Fab")
		)
		(fp_line
			(start -0.67945 0.3048)
			(end -0.120396 0.3048)
			(stroke
				(width 0.1)
				(type default)
			)
			(layer "B.Fab")
		)
		(pad "1" smd circle
			(at 0.40005 0 270)
			(size 0 0)
			(layers "B.Cu" "B.Mask" "B.Paste")
			(net "P3V3_AUX")
		)
		(pad "2" smd circle
			(at -0.40005 0 270)
			(size 0 0)
			(layers "B.Cu" "B.Mask" "B.Paste")
			(net "RST_BMC_SELF_HW_R2")
		)
	)
)
